(kicad_pcb
	(version 20260206)
	(generator "pcbnew")
	(generator_version "10.0")
	(general
		(thickness 1.6)
		(legacy_teardrops no)
	)
	(paper "A4")
	(title_block
		(title "01162023_DA0F0TEBIF0_F0T_Expander_BD_F_brd_V02_OCP.brd")
		(comment 1 "Grand Teton / footprints 3171-3177 of 9728")
	)
	(layers
		(0 "F.Cu" signal "TOP")
		(4 "In1.Cu" signal "GND")
		(6 "In2.Cu" signal "VCC")
		(8 "In3.Cu" signal "VCC1")
		(10 "In4.Cu" signal "GND1")
		(12 "In5.Cu" signal "IN1")
		(14 "In6.Cu" signal "GND2")
		(16 "In7.Cu" signal "IN2")
		(18 "In8.Cu" signal "GND3")
		(20 "In9.Cu" signal "IN3")
		(22 "In10.Cu" signal "GND4")
		(24 "In11.Cu" signal "IN4")
		(26 "In12.Cu" signal "GND5")
		(28 "In13.Cu" signal "IN5")
		(30 "In14.Cu" signal "GND6")
		(32 "In15.Cu" signal "IN6")
		(34 "In16.Cu" signal "GND7")
		(2 "B.Cu" signal "BOTTOM")
		(9 "F.Adhes" user "F.Adhesive")
		(11 "B.Adhes" user "B.Adhesive")
		(13 "F.Paste" user "Package Geometry/Pastemask Top")
		(15 "B.Paste" user "Package Geometry/Pastemask Bottom")
		(5 "F.SilkS" user "Ref Des/Silkscreen Top")
		(7 "B.SilkS" user "Ref Des/Silkscreen Bottom")
		(1 "F.Mask" user "Board Geometry/Soldermask Top")
		(3 "B.Mask" user "Board Geometry/Soldermask Bottom")
		(17 "Dwgs.User" user "User.Drawings")
		(19 "Cmts.User" user "User.Comments")
		(21 "Eco1.User" user "User.Eco1")
		(23 "Eco2.User" user "User.Eco2")
		(25 "Edge.Cuts" user "Board Geometry/Outline")
		(27 "Margin" user)
		(31 "F.CrtYd" user "Package Geometry/Place Bound Top")
		(29 "B.CrtYd" user "Package Geometry/Place Bound Bottom")
		(35 "F.Fab" user "Ref Des/Assembly Top")
		(33 "B.Fab" user "Ref Des/Assembly Bottom")
	)
	(footprint ""
		(layer "F.Cu")
		(at 238.804958 -89.225374 180)
		(property "Reference" "R1019"
			(at 0 0 180)
			(layer "F.SilkS")
			(hide yes)
			(effects
				(font
					(size 1.27 1.27)
				)
			)
		)
		(property "Value" ""
			(at 0 0 180)
			(layer "F.Fab")
			(effects
				(font
					(size 1.27 1.27)
				)
			)
		)
		(duplicate_pad_numbers_are_jumpers no)
		(fp_line
			(start 0.7874 0.4064)
			(end -0.7874 0.4064)
			(stroke
				(width 0.1524)
				(type default)
			)
			(layer "F.SilkS")
		)
		(fp_line
			(start 0.7874 -0.4064)
			(end 0.7874 0.4064)
			(stroke
				(width 0.1524)
				(type default)
			)
			(layer "F.SilkS")
		)
		(fp_line
			(start -0.7874 0.4064)
			(end -0.7874 -0.4064)
			(stroke
				(width 0.1524)
				(type default)
			)
			(layer "F.SilkS")
		)
		(fp_line
			(start -0.7874 -0.4064)
			(end 0.7874 -0.4064)
			(stroke
				(width 0.1524)
				(type default)
			)
			(layer "F.SilkS")
		)
		(fp_line
			(start 0.67945 0.3048)
			(end 0.120396 0.3048)
			(stroke
				(width 0.1)
				(type default)
			)
			(layer "F.Fab")
		)
		(fp_line
			(start 0.67945 -0.3048)
			(end 0.67945 0.3048)
			(stroke
				(width 0.1)
				(type default)
			)
			(layer "F.Fab")
		)
		(fp_line
			(start 0.12065 -0.2794)
			(end 0.12065 -0.3048)
			(stroke
				(width 0.1)
				(type default)
			)
			(layer "F.Fab")
		)
		(fp_line
			(start 0.12065 -0.3048)
			(end 0.67945 -0.3048)
			(stroke
				(width 0.1)
				(type default)
			)
			(layer "F.Fab")
		)
		(fp_line
			(start 0.120396 0.3048)
			(end 0.120396 0.2794)
			(stroke
				(width 0.1)
				(type default)
			)
			(layer "F.Fab")
		)
		(fp_line
			(start 0.120396 0.2794)
			(end -0.12065 0.2794)
			(stroke
				(width 0.1)
				(type default)
			)
			(layer "F.Fab")
		)
		(fp_line
			(start -0.12065 0.3048)
			(end -0.67945 0.3048)
			(stroke
				(width 0.1)
				(type default)
			)
			(layer "F.Fab")
		)
		(fp_line
			(start -0.12065 0.2794)
			(end -0.12065 0.3048)
			(stroke
				(width 0.1)
				(type default)
			)
			(layer "F.Fab")
		)
		(fp_line
			(start -0.12065 -0.2794)
			(end 0.12065 -0.2794)
			(stroke
				(width 0.1)
				(type default)
			)
			(layer "F.Fab")
		)
		(fp_line
			(start -0.12065 -0.305054)
			(end -0.12065 -0.2794)
			(stroke
				(width 0.1)
				(type default)
			)
			(layer "F.Fab")
		)
		(fp_line
			(start -0.67945 0.3048)
			(end -0.67945 -0.305054)
			(stroke
				(width 0.1)
				(type default)
			)
			(layer "F.Fab")
		)
		(fp_line
			(start -0.67945 -0.305054)
			(end -0.12065 -0.305054)
			(stroke
				(width 0.1)
				(type default)
			)
			(layer "F.Fab")
		)
		(pad "1" smd circle
			(at -0.40005 0 180)
			(size 0 0)
			(layers "F.Cu" "F.Mask" "F.Paste")
			(net "GND")
		)
		(pad "2" smd circle
			(at 0.40005 0 180)
			(size 0 0)
			(layers "F.Cu" "F.Mask" "F.Paste")
			(net "PEX_USB_HUB_RREF")
		)
	)
	(footprint ""
		(layer "F.Cu")
		(at 426.32503 -14.735302 180)
		(property "Reference" "C2740"
			(at 0 0 180)
			(layer "F.SilkS")
			(hide yes)
			(effects
				(font
					(size 1.27 1.27)
				)
			)
		)
		(property "Value" ""
			(at 0 0 180)
			(layer "F.Fab")
			(effects
				(font
					(size 1.27 1.27)
				)
			)
		)
		(duplicate_pad_numbers_are_jumpers no)
		(fp_line
			(start 0.7874 0.4064)
			(end -0.7874 0.4064)
			(stroke
				(width 0.1524)
				(type default)
			)
			(layer "F.SilkS")
		)
		(fp_line
			(start 0.7874 -0.4064)
			(end 0.7874 0.4064)
			(stroke
				(width 0.1524)
				(type default)
			)
			(layer "F.SilkS")
		)
		(fp_line
			(start -0.7874 0.4064)
			(end -0.7874 -0.4064)
			(stroke
				(width 0.1524)
				(type default)
			)
			(layer "F.SilkS")
		)
		(fp_line
			(start -0.7874 -0.4064)
			(end 0.7874 -0.4064)
			(stroke
				(width 0.1524)
				(type default)
			)
			(layer "F.SilkS")
		)
		(fp_line
			(start 0.67945 0.3048)
			(end 0.120396 0.3048)
			(stroke
				(width 0.1)
				(type default)
			)
			(layer "F.Fab")
		)
		(fp_line
			(start 0.67945 -0.3048)
			(end 0.67945 0.3048)
			(stroke
				(width 0.1)
				(type default)
			)
			(layer "F.Fab")
		)
		(fp_line
			(start 0.12065 -0.2794)
			(end 0.12065 -0.3048)
			(stroke
				(width 0.1)
				(type default)
			)
			(layer "F.Fab")
		)
		(fp_line
			(start 0.12065 -0.3048)
			(end 0.67945 -0.3048)
			(stroke
				(width 0.1)
				(type default)
			)
			(layer "F.Fab")
		)
		(fp_line
			(start 0.120396 0.3048)
			(end 0.120396 0.2794)
			(stroke
				(width 0.1)
				(type default)
			)
			(layer "F.Fab")
		)
		(fp_line
			(start 0.120396 0.2794)
			(end -0.12065 0.2794)
			(stroke
				(width 0.1)
				(type default)
			)
			(layer "F.Fab")
		)
		(fp_line
			(start -0.12065 0.3048)
			(end -0.67945 0.3048)
			(stroke
				(width 0.1)
				(type default)
			)
			(layer "F.Fab")
		)
		(fp_line
			(start -0.12065 0.2794)
			(end -0.12065 0.3048)
			(stroke
				(width 0.1)
				(type default)
			)
			(layer "F.Fab")
		)
		(fp_line
			(start -0.12065 -0.2794)
			(end 0.12065 -0.2794)
			(stroke
				(width 0.1)
				(type default)
			)
			(layer "F.Fab")
		)
		(fp_line
			(start -0.12065 -0.305054)
			(end -0.12065 -0.2794)
			(stroke
				(width 0.1)
				(type default)
			)
			(layer "F.Fab")
		)
		(fp_line
			(start -0.67945 0.3048)
			(end -0.67945 -0.305054)
			(stroke
				(width 0.1)
				(type default)
			)
			(layer "F.Fab")
		)
		(fp_line
			(start -0.67945 -0.305054)
			(end -0.12065 -0.305054)
			(stroke
				(width 0.1)
				(type default)
			)
			(layer "F.Fab")
		)
		(pad "1" smd circle
			(at -0.40005 0 180)
			(size 0 0)
			(layers "F.Cu" "F.Mask" "F.Paste")
			(net "GND")
		)
		(pad "2" smd circle
			(at 0.40005 0 180)
			(size 0 0)
			(layers "F.Cu" "F.Mask" "F.Paste")
			(net "P3V3_SSD14")
		)
	)
	(footprint ""
		(layer "F.Cu")
		(at 436.95239 -115.400836)
		(property "Reference" "R6043"
			(at 0 0 0)
			(layer "F.SilkS")
			(hide yes)
			(effects
				(font
					(size 1.27 1.27)
				)
			)
		)
		(property "Value" ""
			(at 0 0 0)
			(layer "F.Fab")
			(effects
				(font
					(size 1.27 1.27)
				)
			)
		)
		(duplicate_pad_numbers_are_jumpers no)
		(fp_line
			(start -0.7874 -0.4064)
			(end 0.7874 -0.4064)
			(stroke
				(width 0.1524)
				(type default)
			)
			(layer "F.SilkS")
		)
		(fp_line
			(start -0.7874 0.4064)
			(end -0.7874 -0.4064)
			(stroke
				(width 0.1524)
				(type default)
			)
			(layer "F.SilkS")
		)
		(fp_line
			(start 0.7874 -0.4064)
			(end 0.7874 0.4064)
			(stroke
				(width 0.1524)
				(type default)
			)
			(layer "F.SilkS")
		)
		(fp_line
			(start 0.7874 0.4064)
			(end -0.7874 0.4064)
			(stroke
				(width 0.1524)
				(type default)
			)
			(layer "F.SilkS")
		)
		(fp_line
			(start -0.67945 -0.305054)
			(end -0.12065 -0.305054)
			(stroke
				(width 0.1)
				(type default)
			)
			(layer "F.Fab")
		)
		(fp_line
			(start -0.67945 0.3048)
			(end -0.67945 -0.305054)
			(stroke
				(width 0.1)
				(type default)
			)
			(layer "F.Fab")
		)
		(fp_line
			(start -0.12065 -0.305054)
			(end -0.12065 -0.2794)
			(stroke
				(width 0.1)
				(type default)
			)
			(layer "F.Fab")
		)
		(fp_line
			(start -0.12065 -0.2794)
			(end 0.12065 -0.2794)
			(stroke
				(width 0.1)
				(type default)
			)
			(layer "F.Fab")
		)
		(fp_line
			(start -0.12065 0.2794)
			(end -0.12065 0.3048)
			(stroke
				(width 0.1)
				(type default)
			)
			(layer "F.Fab")
		)
		(fp_line
			(start -0.12065 0.3048)
			(end -0.67945 0.3048)
			(stroke
				(width 0.1)
				(type default)
			)
			(layer "F.Fab")
		)
		(fp_line
			(start 0.120396 0.2794)
			(end -0.12065 0.2794)
			(stroke
				(width 0.1)
				(type default)
			)
			(layer "F.Fab")
		)
		(fp_line
			(start 0.120396 0.3048)
			(end 0.120396 0.2794)
			(stroke
				(width 0.1)
				(type default)
			)
			(layer "F.Fab")
		)
		(fp_line
			(start 0.12065 -0.3048)
			(end 0.67945 -0.3048)
			(stroke
				(width 0.1)
				(type default)
			)
			(layer "F.Fab")
		)
		(fp_line
			(start 0.12065 -0.2794)
			(end 0.12065 -0.3048)
			(stroke
				(width 0.1)
				(type default)
			)
			(layer "F.Fab")
		)
		(fp_line
			(start 0.67945 -0.3048)
			(end 0.67945 0.3048)
			(stroke
				(width 0.1)
				(type default)
			)
			(layer "F.Fab")
		)
		(fp_line
			(start 0.67945 0.3048)
			(end 0.120396 0.3048)
			(stroke
				(width 0.1)
				(type default)
			)
			(layer "F.Fab")
		)
		(pad "1" smd circle
			(at -0.40005 0)
			(size 0 0)
			(layers "F.Cu" "F.Mask" "F.Paste")
			(net "HP_NIC7_EN")
		)
		(pad "2" smd circle
			(at 0.40005 0)
			(size 0 0)
			(layers "F.Cu" "F.Mask" "F.Paste")
			(net "P3V3_NIC7_CO_EN")
		)
	)
	(footprint ""
		(layer "F.Cu")
		(at 238.775748 -36.915598 -90)
		(property "Reference" "R5565"
			(at 0 0 270)
			(layer "F.SilkS")
			(hide yes)
			(effects
				(font
					(size 1.27 1.27)
				)
			)
		)
		(property "Value" ""
			(at 0 0 270)
			(layer "F.Fab")
			(effects
				(font
					(size 1.27 1.27)
				)
			)
		)
		(duplicate_pad_numbers_are_jumpers no)
		(fp_line
			(start -0.7874 0.4064)
			(end -0.7874 -0.4064)
			(stroke
				(width 0.1524)
				(type default)
			)
			(layer "F.SilkS")
		)
		(fp_line
			(start 0.7874 0.4064)
			(end -0.7874 0.4064)
			(stroke
				(width 0.1524)
				(type default)
			)
			(layer "F.SilkS")
		)
		(fp_line
			(start -0.7874 -0.4064)
			(end 0.7874 -0.4064)
			(stroke
				(width 0.1524)
				(type default)
			)
			(layer "F.SilkS")
		)
		(fp_line
			(start 0.7874 -0.4064)
			(end 0.7874 0.4064)
			(stroke
				(width 0.1524)
				(type default)
			)
			(layer "F.SilkS")
		)
		(fp_line
			(start -0.67945 0.3048)
			(end -0.67945 -0.305054)
			(stroke
				(width 0.1)
				(type default)
			)
			(layer "F.Fab")
		)
		(fp_line
			(start -0.12065 0.3048)
			(end -0.67945 0.3048)
			(stroke
				(width 0.1)
				(type default)
			)
			(layer "F.Fab")
		)
		(fp_line
			(start 0.120396 0.3048)
			(end 0.120396 0.2794)
			(stroke
				(width 0.1)
				(type default)
			)
			(layer "F.Fab")
		)
		(fp_line
			(start 0.67945 0.3048)
			(end 0.120396 0.3048)
			(stroke
				(width 0.1)
				(type default)
			)
			(layer "F.Fab")
		)
		(fp_line
			(start -0.12065 0.2794)
			(end -0.12065 0.3048)
			(stroke
				(width 0.1)
				(type default)
			)
			(layer "F.Fab")
		)
		(fp_line
			(start 0.120396 0.2794)
			(end -0.12065 0.2794)
			(stroke
				(width 0.1)
				(type default)
			)
			(layer "F.Fab")
		)
		(fp_line
			(start -0.12065 -0.2794)
			(end 0.12065 -0.2794)
			(stroke
				(width 0.1)
				(type default)
			)
			(layer "F.Fab")
		)
		(fp_line
			(start 0.12065 -0.2794)
			(end 0.12065 -0.3048)
			(stroke
				(width 0.1)
				(type default)
			)
			(layer "F.Fab")
		)
		(fp_line
			(start 0.12065 -0.3048)
			(end 0.67945 -0.3048)
			(stroke
				(width 0.1)
				(type default)
			)
			(layer "F.Fab")
		)
		(fp_line
			(start 0.67945 -0.3048)
			(end 0.67945 0.3048)
			(stroke
				(width 0.1)
				(type default)
			)
			(layer "F.Fab")
		)
		(fp_line
			(start -0.67945 -0.305054)
			(end -0.12065 -0.305054)
			(stroke
				(width 0.1)
				(type default)
			)
			(layer "F.Fab")
		)
		(fp_line
			(start -0.12065 -0.305054)
			(end -0.12065 -0.2794)
			(stroke
				(width 0.1)
				(type default)
			)
			(layer "F.Fab")
		)
		(pad "1" smd circle
			(at -0.40005 0 270)
			(size 0 0)
			(layers "F.Cu" "F.Mask" "F.Paste")
			(net "PRSNT_SSD8_R1_N")
		)
		(pad "2" smd circle
			(at 0.40005 0 270)
			(size 0 0)
			(layers "F.Cu" "F.Mask" "F.Paste")
			(net "PRSNT_SSD8_R_N")
		)
	)
	(footprint ""
		(layer "F.Cu")
		(at 211.491322 -227.225606 -90)
		(property "Reference" "R2742"
			(at 0 0 270)
			(layer "F.SilkS")
			(hide yes)
			(effects
				(font
					(size 1.27 1.27)
				)
			)
		)
		(property "Value" ""
			(at 0 0 270)
			(layer "F.Fab")
			(effects
				(font
					(size 1.27 1.27)
				)
			)
		)
		(duplicate_pad_numbers_are_jumpers no)
		(fp_line
			(start -0.7874 0.4064)
			(end -0.7874 -0.4064)
			(stroke
				(width 0.1524)
				(type default)
			)
			(layer "F.SilkS")
		)
		(fp_line
			(start 0.7874 0.4064)
			(end -0.7874 0.4064)
			(stroke
				(width 0.1524)
				(type default)
			)
			(layer "F.SilkS")
		)
		(fp_line
			(start -0.7874 -0.4064)
			(end 0.7874 -0.4064)
			(stroke
				(width 0.1524)
				(type default)
			)
			(layer "F.SilkS")
		)
		(fp_line
			(start 0.7874 -0.4064)
			(end 0.7874 0.4064)
			(stroke
				(width 0.1524)
				(type default)
			)
			(layer "F.SilkS")
		)
		(fp_line
			(start -0.67945 0.3048)
			(end -0.67945 -0.305054)
			(stroke
				(width 0.1)
				(type default)
			)
			(layer "F.Fab")
		)
		(fp_line
			(start -0.12065 0.3048)
			(end -0.67945 0.3048)
			(stroke
				(width 0.1)
				(type default)
			)
			(layer "F.Fab")
		)
		(fp_line
			(start 0.120396 0.3048)
			(end 0.120396 0.2794)
			(stroke
				(width 0.1)
				(type default)
			)
			(layer "F.Fab")
		)
		(fp_line
			(start 0.67945 0.3048)
			(end 0.120396 0.3048)
			(stroke
				(width 0.1)
				(type default)
			)
			(layer "F.Fab")
		)
		(fp_line
			(start -0.12065 0.2794)
			(end -0.12065 0.3048)
			(stroke
				(width 0.1)
				(type default)
			)
			(layer "F.Fab")
		)
		(fp_line
			(start 0.120396 0.2794)
			(end -0.12065 0.2794)
			(stroke
				(width 0.1)
				(type default)
			)
			(layer "F.Fab")
		)
		(fp_line
			(start -0.12065 -0.2794)
			(end 0.12065 -0.2794)
			(stroke
				(width 0.1)
				(type default)
			)
			(layer "F.Fab")
		)
		(fp_line
			(start 0.12065 -0.2794)
			(end 0.12065 -0.3048)
			(stroke
				(width 0.1)
				(type default)
			)
			(layer "F.Fab")
		)
		(fp_line
			(start 0.12065 -0.3048)
			(end 0.67945 -0.3048)
			(stroke
				(width 0.1)
				(type default)
			)
			(layer "F.Fab")
		)
		(fp_line
			(start 0.67945 -0.3048)
			(end 0.67945 0.3048)
			(stroke
				(width 0.1)
				(type default)
			)
			(layer "F.Fab")
		)
		(fp_line
			(start -0.67945 -0.305054)
			(end -0.12065 -0.305054)
			(stroke
				(width 0.1)
				(type default)
			)
			(layer "F.Fab")
		)
		(fp_line
			(start -0.12065 -0.305054)
			(end -0.12065 -0.2794)
			(stroke
				(width 0.1)
				(type default)
			)
			(layer "F.Fab")
		)
		(pad "1" smd circle
			(at -0.40005 0 270)
			(size 0 0)
			(layers "F.Cu" "F.Mask" "F.Paste")
			(net "UART_MB_BIC_TX_BUF_R")
		)
		(pad "2" smd circle
			(at 0.40005 0 270)
			(size 0 0)
			(layers "F.Cu" "F.Mask" "F.Paste")
			(net "UART_MB_BIC_TX_BUF")
		)
	)
	(footprint ""
		(layer "F.Cu")
		(at 242.460018 -236.682026 90)
		(property "Reference" "R6225"
			(at 0 0 90)
			(layer "F.SilkS")
			(hide yes)
			(effects
				(font
					(size 1.27 1.27)
				)
			)
		)
		(property "Value" ""
			(at 0 0 90)
			(layer "F.Fab")
			(effects
				(font
					(size 1.27 1.27)
				)
			)
		)
		(duplicate_pad_numbers_are_jumpers no)
		(fp_line
			(start 0.7874 -0.4064)
			(end 0.7874 0.4064)
			(stroke
				(width 0.1524)
				(type default)
			)
			(layer "F.SilkS")
		)
		(fp_line
			(start -0.7874 -0.4064)
			(end 0.7874 -0.4064)
			(stroke
				(width 0.1524)
				(type default)
			)
			(layer "F.SilkS")
		)
		(fp_line
			(start 0.7874 0.4064)
			(end -0.7874 0.4064)
			(stroke
				(width 0.1524)
				(type default)
			)
			(layer "F.SilkS")
		)
		(fp_line
			(start -0.7874 0.4064)
			(end -0.7874 -0.4064)
			(stroke
				(width 0.1524)
				(type default)
			)
			(layer "F.SilkS")
		)
		(fp_line
			(start -0.12065 -0.305054)
			(end -0.12065 -0.2794)
			(stroke
				(width 0.1)
				(type default)
			)
			(layer "F.Fab")
		)
		(fp_line
			(start -0.67945 -0.305054)
			(end -0.12065 -0.305054)
			(stroke
				(width 0.1)
				(type default)
			)
			(layer "F.Fab")
		)
		(fp_line
			(start 0.67945 -0.3048)
			(end 0.67945 0.3048)
			(stroke
				(width 0.1)
				(type default)
			)
			(layer "F.Fab")
		)
		(fp_line
			(start 0.12065 -0.3048)
			(end 0.67945 -0.3048)
			(stroke
				(width 0.1)
				(type default)
			)
			(layer "F.Fab")
		)
		(fp_line
			(start 0.12065 -0.2794)
			(end 0.12065 -0.3048)
			(stroke
				(width 0.1)
				(type default)
			)
			(layer "F.Fab")
		)
		(fp_line
			(start -0.12065 -0.2794)
			(end 0.12065 -0.2794)
			(stroke
				(width 0.1)
				(type default)
			)
			(layer "F.Fab")
		)
		(fp_line
			(start 0.120396 0.2794)
			(end -0.12065 0.2794)
			(stroke
				(width 0.1)
				(type default)
			)
			(layer "F.Fab")
		)
		(fp_line
			(start -0.12065 0.2794)
			(end -0.12065 0.3048)
			(stroke
				(width 0.1)
				(type default)
			)
			(layer "F.Fab")
		)
		(fp_line
			(start 0.67945 0.3048)
			(end 0.120396 0.3048)
			(stroke
				(width 0.1)
				(type default)
			)
			(layer "F.Fab")
		)
		(fp_line
			(start 0.120396 0.3048)
			(end 0.120396 0.2794)
			(stroke
				(width 0.1)
				(type default)
			)
			(layer "F.Fab")
		)
		(fp_line
			(start -0.12065 0.3048)
			(end -0.67945 0.3048)
			(stroke
				(width 0.1)
				(type default)
			)
			(layer "F.Fab")
		)
		(fp_line
			(start -0.67945 0.3048)
			(end -0.67945 -0.305054)
			(stroke
				(width 0.1)
				(type default)
			)
			(layer "F.Fab")
		)
		(pad "1" smd circle
			(at -0.40005 0 90)
			(size 0 0)
			(layers "F.Cu" "F.Mask" "F.Paste")
			(net "P3V3_AUX")
		)
		(pad "2" smd circle
			(at 0.40005 0 90)
			(size 0 0)
			(layers "F.Cu" "F.Mask" "F.Paste")
			(net "BIC_RECOVER_IOEXP_A0")
		)
	)
	(footprint ""
		(layer "F.Cu")
		(at 302.82007 -15.649956 180)
		(property "Reference" "H121"
			(at -3.525012 -2.4257 0)
			(unlocked yes)
			(layer "B.SilkS")
			(effects
				(font
					(size 0.7874 0.5842)
					(thickness 0.1524)
				)
				(justify left mirror)
			)
		)
		(property "Value" ""
			(at 0 0 180)
			(layer "F.Fab")
			(effects
				(font
					(size 1.27 1.27)
				)
			)
		)
		(duplicate_pad_numbers_are_jumpers no)
		(pad "1" thru_hole rect
			(at 0 0 180)
			(size 4.2164 5.0038)
			(drill 2.0066
				(offset 0.099822 0)
			)
			(layers "*.Cu" "*.Mask")
			(remove_unused_layers no)
			(net "Net_8542")
			(clearance -0.8509)
			(padstack
				(mode front_inner_back)
				(layer "Inner"
					(shape circle)
					(size 4.0132 4.0132)
					(clearance -0.7493)
				)
				(layer "B.Cu"
					(shape circle)
					(size 4.0132 4.0132)
					(clearance -0.7493)
				)
			)
		)
	)
)
